(kicad_pcb
	(version 20260206)
	(generator "pcbnew")
	(generator_version "10.0")
	(general
		(thickness 1.6)
		(legacy_teardrops no)
	)
	(paper "A4")
	(title_block
		(title "Bryce Canyon_IOM_M2_16342-2_OCP.brd")
		(comment 1 "Bryce Canyon / footprints 910-916 of 1146")
	)
	(layers
		(0 "F.Cu" signal "TOP")
		(4 "In1.Cu" signal "L2GND")
		(6 "In2.Cu" signal "L3")
		(8 "In3.Cu" signal "L4VCC")
		(10 "In4.Cu" signal "L5VCC")
		(12 "In5.Cu" signal "L6")
		(14 "In6.Cu" signal "L7GND")
		(2 "B.Cu" signal "BOTTOM")
		(9 "F.Adhes" user "F.Adhesive")
		(11 "B.Adhes" user "B.Adhesive")
		(13 "F.Paste" user "Package Geometry/Pastemask Top")
		(15 "B.Paste" user "Package Geometry/Pastemask Bottom")
		(5 "F.SilkS" user "Ref Des/Silkscreen Top")
		(7 "B.SilkS" user "Ref Des/Silkscreen Bottom")
		(1 "F.Mask" user "Board Geometry/Soldermask Top")
		(3 "B.Mask" user "Board Geometry/Soldermask Bottom")
		(17 "Dwgs.User" user "User.Drawings")
		(19 "Cmts.User" user "User.Comments")
		(21 "Eco1.User" user "User.Eco1")
		(23 "Eco2.User" user "User.Eco2")
		(25 "Edge.Cuts" user "Board Geometry/Outline")
		(27 "Margin" user)
		(31 "F.CrtYd" user "Package Geometry/Place Bound Top")
		(29 "B.CrtYd" user "Package Geometry/Place Bound Bottom")
		(35 "F.Fab" user "Ref Des/Assembly Top")
		(33 "B.Fab" user "Ref Des/Assembly Bottom")
	)
	(footprint ""
		(layer "B.Cu")
		(at 16.294354 -131.007358 180)
		(property "Reference" "R259"
			(at 0 0 0)
			(layer "B.SilkS")
			(hide yes)
			(effects
				(font
					(size 1.27 1.27)
				)
				(justify mirror)
			)
		)
		(property "Value" "120R2F-GP"
			(at -0.064008 -3.993896 180)
			(unlocked yes)
			(layer "B.Fab")
			(hide yes)
			(effects
				(font
					(size 1.016 1.016)
					(thickness 0.1524)
				)
				(justify mirror)
			)
		)
		(property "Device Type" "R402H16"
			(at -0.064008 -5.517896 180)
			(unlocked yes)
			(layer "B.Fab")
			(hide yes)
			(effects
				(font
					(size 1.016 1.016)
					(thickness 0.1524)
				)
				(justify mirror)
			)
		)
		(duplicate_pad_numbers_are_jumpers no)
		(fp_line
			(start 0.508 -0.9398)
			(end 0.508 0.9398)
			(stroke
				(width 0.1524)
				(type default)
			)
			(layer "B.SilkS")
		)
		(fp_line
			(start -0.508 -0.9398)
			(end 0.508 -0.9398)
			(stroke
				(width 0.1524)
				(type default)
			)
			(layer "B.SilkS")
		)
		(fp_rect
			(start 0.508 0.9398)
			(end -0.508 -0.9398)
			(stroke
				(width 0)
				(type default)
			)
			(fill no)
			(layer "B.CrtYd")
		)
		(fp_rect
			(start 0.508 0.9398)
			(end -0.508 -0.9398)
			(stroke
				(width 0)
				(type default)
			)
			(fill no)
			(layer "B.Fab")
		)
		(pad "1" smd custom
			(at 0 -0.4445)
			(size 0.1397 0.1397)
			(layers "B.Cu" "B.Mask" "B.Paste")
			(net "MEMA_12")
			(options
				(clearance outline)
				(anchor circle)
			)
			(primitives
				(gr_poly
					(pts
						(arc
							(start -0.1778 0.2794)
							(mid -0.249642 0.249642)
							(end -0.2794 0.1778)
						)
						(arc
							(start -0.2794 -0.1778)
							(mid -0.249642 -0.249642)
							(end -0.1778 -0.2794)
						)
						(arc
							(start 0.1778 -0.2794)
							(mid 0.249642 -0.249642)
							(end 0.2794 -0.1778)
						)
						(arc
							(start 0.2794 0.1778)
							(mid 0.249642 0.249642)
							(end 0.1778 0.2794)
						)
					)
					(width 0)
					(fill yes)
				)
			)
		)
		(pad "2" smd custom
			(at 0 0.4445)
			(size 0.1397 0.1397)
			(layers "B.Cu" "B.Mask" "B.Paste")
			(net "P1V2_STBY")
			(options
				(clearance outline)
				(anchor circle)
			)
			(primitives
				(gr_poly
					(pts
						(arc
							(start -0.1778 0.2794)
							(mid -0.249642 0.249642)
							(end -0.2794 0.1778)
						)
						(arc
							(start -0.2794 -0.1778)
							(mid -0.249642 -0.249642)
							(end -0.1778 -0.2794)
						)
						(arc
							(start 0.1778 -0.2794)
							(mid 0.249642 -0.249642)
							(end 0.2794 -0.1778)
						)
						(arc
							(start 0.2794 0.1778)
							(mid 0.249642 0.249642)
							(end 0.1778 0.2794)
						)
					)
					(width 0)
					(fill yes)
				)
			)
		)
	)
	(footprint ""
		(layer "B.Cu")
		(at 22.606 -172.0342 90)
		(property "Reference" "C998"
			(at 0 0 90)
			(layer "B.SilkS")
			(hide yes)
			(effects
				(font
					(size 1.27 1.27)
				)
				(justify mirror)
			)
		)
		(property "Value" "SC1U16V3KX-5GP"
			(at 0 -2.8194 90)
			(unlocked yes)
			(layer "B.Fab")
			(hide yes)
			(effects
				(font
					(size 1.016 1.016)
					(thickness 0.1524)
				)
				(justify mirror)
			)
		)
		(property "Device Type" "C603H36"
			(at 0 -4.3434 90)
			(unlocked yes)
			(layer "B.Fab")
			(hide yes)
			(effects
				(font
					(size 1.016 1.016)
					(thickness 0.1524)
				)
				(justify mirror)
			)
		)
		(duplicate_pad_numbers_are_jumpers no)
		(fp_line
			(start -0.508 0)
			(end 0.508 0)
			(stroke
				(width 0.2032)
				(type default)
			)
			(layer "B.SilkS")
		)
		(fp_rect
			(start 0.5842 1.3335)
			(end -0.5842 -1.3335)
			(stroke
				(width 0)
				(type default)
			)
			(fill no)
			(layer "B.CrtYd")
		)
		(fp_rect
			(start 0.5842 1.3335)
			(end -0.5842 -1.3335)
			(stroke
				(width 0)
				(type default)
			)
			(fill no)
			(layer "B.Fab")
		)
		(pad "1" smd custom
			(at 0 -0.762 270)
			(size 0.2159 0.2159)
			(layers "B.Cu" "B.Mask" "B.Paste")
			(net "P1V8_STBY")
			(options
				(clearance outline)
				(anchor circle)
			)
			(primitives
				(gr_poly
					(pts
						(arc
							(start -0.3302 0.4318)
							(mid -0.402042 0.402042)
							(end -0.4318 0.3302)
						)
						(arc
							(start -0.4318 -0.3302)
							(mid -0.402042 -0.402042)
							(end -0.3302 -0.4318)
						)
						(arc
							(start 0.3302 -0.4318)
							(mid 0.402042 -0.402042)
							(end 0.4318 -0.3302)
						)
						(arc
							(start 0.4318 0.3302)
							(mid 0.402042 0.402042)
							(end 0.3302 0.4318)
						)
					)
					(width 0)
					(fill yes)
				)
			)
		)
		(pad "2" smd custom
			(at 0 0.762 270)
			(size 0.2159 0.2159)
			(layers "B.Cu" "B.Mask" "B.Paste")
			(net "GND")
			(options
				(clearance outline)
				(anchor circle)
			)
			(primitives
				(gr_poly
					(pts
						(arc
							(start -0.3302 0.4318)
							(mid -0.402042 0.402042)
							(end -0.4318 0.3302)
						)
						(arc
							(start -0.4318 -0.3302)
							(mid -0.402042 -0.402042)
							(end -0.3302 -0.4318)
						)
						(arc
							(start 0.3302 -0.4318)
							(mid 0.402042 -0.402042)
							(end 0.4318 -0.3302)
						)
						(arc
							(start 0.4318 0.3302)
							(mid 0.402042 0.402042)
							(end 0.3302 0.4318)
						)
					)
					(width 0)
					(fill yes)
				)
			)
		)
	)
	(footprint ""
		(layer "B.Cu")
		(at 81.89595 -141.750542 -90)
		(property "Reference" "R128"
			(at 0 0 90)
			(layer "B.SilkS")
			(hide yes)
			(effects
				(font
					(size 1.27 1.27)
				)
				(justify mirror)
			)
		)
		(property "Value" "0R2J-2-GP"
			(at -0.064008 -3.993896 270)
			(unlocked yes)
			(layer "B.Fab")
			(hide yes)
			(effects
				(font
					(size 1.016 1.016)
					(thickness 0.1524)
				)
				(justify mirror)
			)
		)
		(property "Device Type" "R402H16"
			(at -0.064008 -5.517896 270)
			(unlocked yes)
			(layer "B.Fab")
			(hide yes)
			(effects
				(font
					(size 1.016 1.016)
					(thickness 0.1524)
				)
				(justify mirror)
			)
		)
		(duplicate_pad_numbers_are_jumpers no)
		(fp_line
			(start -0.508 -0.9398)
			(end 0.508 -0.9398)
			(stroke
				(width 0.1524)
				(type default)
			)
			(layer "B.SilkS")
		)
		(fp_line
			(start 0.508 -0.9398)
			(end 0.508 0.9398)
			(stroke
				(width 0.1524)
				(type default)
			)
			(layer "B.SilkS")
		)
		(fp_rect
			(start 0.508 0.9398)
			(end -0.508 -0.9398)
			(stroke
				(width 0)
				(type default)
			)
			(fill no)
			(layer "B.CrtYd")
		)
		(fp_rect
			(start 0.508 0.9398)
			(end -0.508 -0.9398)
			(stroke
				(width 0)
				(type default)
			)
			(fill no)
			(layer "B.Fab")
		)
		(pad "1" smd custom
			(at 0 -0.4445 90)
			(size 0.1397 0.1397)
			(layers "B.Cu" "B.Mask" "B.Paste")
			(net "I2C_EXP_LOC_SDA")
			(options
				(clearance outline)
				(anchor circle)
			)
			(primitives
				(gr_poly
					(pts
						(arc
							(start -0.1778 0.2794)
							(mid -0.249642 0.249642)
							(end -0.2794 0.1778)
						)
						(arc
							(start -0.2794 -0.1778)
							(mid -0.249642 -0.249642)
							(end -0.1778 -0.2794)
						)
						(arc
							(start 0.1778 -0.2794)
							(mid 0.249642 -0.249642)
							(end 0.2794 -0.1778)
						)
						(arc
							(start 0.2794 0.1778)
							(mid 0.249642 0.249642)
							(end 0.1778 0.2794)
						)
					)
					(width 0)
					(fill yes)
				)
			)
		)
		(pad "2" smd custom
			(at 0 0.4445 90)
			(size 0.1397 0.1397)
			(layers "B.Cu" "B.Mask" "B.Paste")
			(net "I2C_EXP_LOC_SDA_R")
			(options
				(clearance outline)
				(anchor circle)
			)
			(primitives
				(gr_poly
					(pts
						(arc
							(start -0.1778 0.2794)
							(mid -0.249642 0.249642)
							(end -0.2794 0.1778)
						)
						(arc
							(start -0.2794 -0.1778)
							(mid -0.249642 -0.249642)
							(end -0.1778 -0.2794)
						)
						(arc
							(start 0.1778 -0.2794)
							(mid 0.249642 -0.249642)
							(end 0.2794 -0.1778)
						)
						(arc
							(start 0.2794 0.1778)
							(mid 0.249642 0.249642)
							(end 0.1778 0.2794)
						)
					)
					(width 0)
					(fill yes)
				)
			)
		)
	)
	(footprint ""
		(layer "B.Cu")
		(at 38.055296 -137.869676)
		(property "Reference" "TP17"
			(at 0 0 0)
			(layer "B.SilkS")
			(hide yes)
			(effects
				(font
					(size 1.27 1.27)
				)
				(justify mirror)
			)
		)
		(property "Value" "TPAD28-2-GP"
			(at 0.0127 -1.6637 0)
			(unlocked yes)
			(layer "B.Fab")
			(hide yes)
			(effects
				(font
					(size 1.016 1.016)
					(thickness 0.1524)
				)
				(justify mirror)
			)
		)
		(property "Device Type" "TPAD28"
			(at 0.0127 -3.1877 0)
			(unlocked yes)
			(layer "B.Fab")
			(hide yes)
			(effects
				(font
					(size 1.016 1.016)
					(thickness 0.1524)
				)
				(justify mirror)
			)
		)
		(duplicate_pad_numbers_are_jumpers no)
		(fp_poly
			(pts
				(arc
					(start 0.3556 0)
					(mid -0.3556 0)
					(end 0.3556 0)
				)
			)
			(stroke
				(width 0)
				(type default)
			)
			(fill no)
			(layer "B.CrtYd")
		)
		(fp_poly
			(pts
				(arc
					(start 0.6096 0)
					(mid -0.6096 0)
					(end 0.6096 0)
				)
			)
			(stroke
				(width 0)
				(type default)
			)
			(fill no)
			(layer "B.Fab")
		)
		(pad "1" smd circle
			(at 0 0 180)
			(size 0.7112 0.7112)
			(layers "B.Cu" "B.Mask" "B.Paste")
			(net "TP_BMC_GPIOR3")
		)
	)
	(footprint ""
		(layer "B.Cu")
		(at 12.091924 -138.144504 90)
		(property "Reference" "R247"
			(at 0 0 90)
			(layer "B.SilkS")
			(hide yes)
			(effects
				(font
					(size 1.27 1.27)
				)
				(justify mirror)
			)
		)
		(property "Value" "120R2F-GP"
			(at -0.064008 -3.993896 90)
			(unlocked yes)
			(layer "B.Fab")
			(hide yes)
			(effects
				(font
					(size 1.016 1.016)
					(thickness 0.1524)
				)
				(justify mirror)
			)
		)
		(property "Device Type" "R402H16"
			(at -0.064008 -5.517896 90)
			(unlocked yes)
			(layer "B.Fab")
			(hide yes)
			(effects
				(font
					(size 1.016 1.016)
					(thickness 0.1524)
				)
				(justify mirror)
			)
		)
		(duplicate_pad_numbers_are_jumpers no)
		(fp_line
			(start 0.508 -0.9398)
			(end 0.508 0.9398)
			(stroke
				(width 0.1524)
				(type default)
			)
			(layer "B.SilkS")
		)
		(fp_line
			(start -0.508 -0.9398)
			(end 0.508 -0.9398)
			(stroke
				(width 0.1524)
				(type default)
			)
			(layer "B.SilkS")
		)
		(fp_rect
			(start 0.508 0.9398)
			(end -0.508 -0.9398)
			(stroke
				(width 0)
				(type default)
			)
			(fill no)
			(layer "B.CrtYd")
		)
		(fp_rect
			(start 0.508 0.9398)
			(end -0.508 -0.9398)
			(stroke
				(width 0)
				(type default)
			)
			(fill no)
			(layer "B.Fab")
		)
		(pad "1" smd custom
			(at 0 -0.4445 270)
			(size 0.1397 0.1397)
			(layers "B.Cu" "B.Mask" "B.Paste")
			(net "MEMA_6")
			(options
				(clearance outline)
				(anchor circle)
			)
			(primitives
				(gr_poly
					(pts
						(arc
							(start -0.1778 0.2794)
							(mid -0.249642 0.249642)
							(end -0.2794 0.1778)
						)
						(arc
							(start -0.2794 -0.1778)
							(mid -0.249642 -0.249642)
							(end -0.1778 -0.2794)
						)
						(arc
							(start 0.1778 -0.2794)
							(mid 0.249642 -0.249642)
							(end 0.2794 -0.1778)
						)
						(arc
							(start 0.2794 0.1778)
							(mid 0.249642 0.249642)
							(end 0.1778 0.2794)
						)
					)
					(width 0)
					(fill yes)
				)
			)
		)
		(pad "2" smd custom
			(at 0 0.4445 270)
			(size 0.1397 0.1397)
			(layers "B.Cu" "B.Mask" "B.Paste")
			(net "P1V2_STBY")
			(options
				(clearance outline)
				(anchor circle)
			)
			(primitives
				(gr_poly
					(pts
						(arc
							(start -0.1778 0.2794)
							(mid -0.249642 0.249642)
							(end -0.2794 0.1778)
						)
						(arc
							(start -0.2794 -0.1778)
							(mid -0.249642 -0.249642)
							(end -0.1778 -0.2794)
						)
						(arc
							(start 0.1778 -0.2794)
							(mid 0.249642 -0.249642)
							(end 0.2794 -0.1778)
						)
						(arc
							(start 0.2794 0.1778)
							(mid 0.249642 0.249642)
							(end 0.1778 0.2794)
						)
					)
					(width 0)
					(fill yes)
				)
			)
		)
	)
	(footprint ""
		(layer "B.Cu")
		(at 40.206676 -127.978916)
		(property "Reference" "R348"
			(at 0 0 0)
			(layer "B.SilkS")
			(hide yes)
			(effects
				(font
					(size 1.27 1.27)
				)
				(justify mirror)
			)
		)
		(property "Value" "0R2J-2-GP"
			(at -0.064008 -3.993896 0)
			(unlocked yes)
			(layer "B.Fab")
			(hide yes)
			(effects
				(font
					(size 1.016 1.016)
					(thickness 0.1524)
				)
				(justify mirror)
			)
		)
		(property "Device Type" "R402H16"
			(at -0.064008 -5.517896 0)
			(unlocked yes)
			(layer "B.Fab")
			(hide yes)
			(effects
				(font
					(size 1.016 1.016)
					(thickness 0.1524)
				)
				(justify mirror)
			)
		)
		(duplicate_pad_numbers_are_jumpers no)
		(fp_line
			(start -0.508 -0.9398)
			(end 0.508 -0.9398)
			(stroke
				(width 0.1524)
				(type default)
			)
			(layer "B.SilkS")
		)
		(fp_line
			(start 0.508 -0.9398)
			(end 0.508 0.9398)
			(stroke
				(width 0.1524)
				(type default)
			)
			(layer "B.SilkS")
		)
		(fp_rect
			(start 0.508 0.9398)
			(end -0.508 -0.9398)
			(stroke
				(width 0)
				(type default)
			)
			(fill no)
			(layer "B.CrtYd")
		)
		(fp_rect
			(start 0.508 0.9398)
			(end -0.508 -0.9398)
			(stroke
				(width 0)
				(type default)
			)
			(fill no)
			(layer "B.Fab")
		)
		(pad "1" smd custom
			(at 0 -0.4445 180)
			(size 0.1397 0.1397)
			(layers "B.Cu" "B.Mask" "B.Paste")
			(net "BMC_EXTRST_N")
			(options
				(clearance outline)
				(anchor circle)
			)
			(primitives
				(gr_poly
					(pts
						(arc
							(start -0.1778 0.2794)
							(mid -0.249642 0.249642)
							(end -0.2794 0.1778)
						)
						(arc
							(start -0.2794 -0.1778)
							(mid -0.249642 -0.249642)
							(end -0.1778 -0.2794)
						)
						(arc
							(start 0.1778 -0.2794)
							(mid 0.249642 -0.249642)
							(end 0.2794 -0.1778)
						)
						(arc
							(start 0.2794 0.1778)
							(mid 0.249642 0.249642)
							(end 0.1778 0.2794)
						)
					)
					(width 0)
					(fill yes)
				)
			)
		)
		(pad "2" smd custom
			(at 0 0.4445 180)
			(size 0.1397 0.1397)
			(layers "B.Cu" "B.Mask" "B.Paste")
			(net "RST_BMC_EXTRST_N_1")
			(options
				(clearance outline)
				(anchor circle)
			)
			(primitives
				(gr_poly
					(pts
						(arc
							(start -0.1778 0.2794)
							(mid -0.249642 0.249642)
							(end -0.2794 0.1778)
						)
						(arc
							(start -0.2794 -0.1778)
							(mid -0.249642 -0.249642)
							(end -0.1778 -0.2794)
						)
						(arc
							(start 0.1778 -0.2794)
							(mid 0.249642 -0.249642)
							(end 0.2794 -0.1778)
						)
						(arc
							(start 0.2794 0.1778)
							(mid 0.249642 0.249642)
							(end 0.1778 0.2794)
						)
					)
					(width 0)
					(fill yes)
				)
			)
		)
	)
	(footprint ""
		(layer "B.Cu")
		(at 37.795962 -129.384806 90)
		(property "Reference" "R501"
			(at 0 0 90)
			(layer "B.SilkS")
			(hide yes)
			(effects
				(font
					(size 1.27 1.27)
				)
				(justify mirror)
			)
		)
		(property "Value" "4K7R2F-GP"
			(at -0.064008 -3.993896 90)
			(unlocked yes)
			(layer "B.Fab")
			(hide yes)
			(effects
				(font
					(size 1.016 1.016)
					(thickness 0.1524)
				)
				(justify mirror)
			)
		)
		(property "Device Type" "R402H16"
			(at -0.064008 -5.517896 90)
			(unlocked yes)
			(layer "B.Fab")
			(hide yes)
			(effects
				(font
					(size 1.016 1.016)
					(thickness 0.1524)
				)
				(justify mirror)
			)
		)
		(duplicate_pad_numbers_are_jumpers no)
		(fp_line
			(start 0.508 -0.9398)
			(end 0.508 0.9398)
			(stroke
				(width 0.1524)
				(type default)
			)
			(layer "B.SilkS")
		)
		(fp_line
			(start -0.508 -0.9398)
			(end 0.508 -0.9398)
			(stroke
				(width 0.1524)
				(type default)
			)
			(layer "B.SilkS")
		)
		(fp_rect
			(start 0.508 0.9398)
			(end -0.508 -0.9398)
			(stroke
				(width 0)
				(type default)
			)
			(fill no)
			(layer "B.CrtYd")
		)
		(fp_rect
			(start 0.508 0.9398)
			(end -0.508 -0.9398)
			(stroke
				(width 0)
				(type default)
			)
			(fill no)
			(layer "B.Fab")
		)
		(pad "1" smd custom
			(at 0 -0.4445 270)
			(size 0.1397 0.1397)
			(layers "B.Cu" "B.Mask" "B.Paste")
			(net "P3V3_STBY")
			(options
				(clearance outline)
				(anchor circle)
			)
			(primitives
				(gr_poly
					(pts
						(arc
							(start -0.1778 0.2794)
							(mid -0.249642 0.249642)
							(end -0.2794 0.1778)
						)
						(arc
							(start -0.2794 -0.1778)
							(mid -0.249642 -0.249642)
							(end -0.1778 -0.2794)
						)
						(arc
							(start 0.1778 -0.2794)
							(mid 0.249642 -0.249642)
							(end 0.2794 -0.1778)
						)
						(arc
							(start 0.2794 0.1778)
							(mid 0.249642 0.249642)
							(end 0.1778 0.2794)
						)
					)
					(width 0)
					(fill yes)
				)
			)
		)
		(pad "2" smd custom
			(at 0 0.4445 270)
			(size 0.1397 0.1397)
			(layers "B.Cu" "B.Mask" "B.Paste")
			(net "BMC_ML_PWR_BLUE_LED")
			(options
				(clearance outline)
				(anchor circle)
			)
			(primitives
				(gr_poly
					(pts
						(arc
							(start -0.1778 0.2794)
							(mid -0.249642 0.249642)
							(end -0.2794 0.1778)
						)
						(arc
							(start -0.2794 -0.1778)
							(mid -0.249642 -0.249642)
							(end -0.1778 -0.2794)
						)
						(arc
							(start 0.1778 -0.2794)
							(mid 0.249642 -0.249642)
							(end 0.2794 -0.1778)
						)
						(arc
							(start 0.2794 0.1778)
							(mid 0.249642 0.249642)
							(end 0.1778 0.2794)
						)
					)
					(width 0)
					(fill yes)
				)
			)
		)
	)
)
